(kicad_pcb
	(version 20260206)
	(generator "pcbnew")
	(generator_version "10.0")
	(general
		(thickness 1.6)
		(legacy_teardrops no)
	)
	(paper "A4")
	(title_block
		(title "01162023_DA0F0TEBIF0_F0T_Expander_BD_F_brd_V02_OCP.brd")
		(comment 1 "Grand Teton / footprints 5835-5841 of 9728")
	)
	(layers
		(0 "F.Cu" signal "TOP")
		(4 "In1.Cu" signal "GND")
		(6 "In2.Cu" signal "VCC")
		(8 "In3.Cu" signal "VCC1")
		(10 "In4.Cu" signal "GND1")
		(12 "In5.Cu" signal "IN1")
		(14 "In6.Cu" signal "GND2")
		(16 "In7.Cu" signal "IN2")
		(18 "In8.Cu" signal "GND3")
		(20 "In9.Cu" signal "IN3")
		(22 "In10.Cu" signal "GND4")
		(24 "In11.Cu" signal "IN4")
		(26 "In12.Cu" signal "GND5")
		(28 "In13.Cu" signal "IN5")
		(30 "In14.Cu" signal "GND6")
		(32 "In15.Cu" signal "IN6")
		(34 "In16.Cu" signal "GND7")
		(2 "B.Cu" signal "BOTTOM")
		(9 "F.Adhes" user "F.Adhesive")
		(11 "B.Adhes" user "B.Adhesive")
		(13 "F.Paste" user "Package Geometry/Pastemask Top")
		(15 "B.Paste" user "Package Geometry/Pastemask Bottom")
		(5 "F.SilkS" user "Ref Des/Silkscreen Top")
		(7 "B.SilkS" user "Ref Des/Silkscreen Bottom")
		(1 "F.Mask" user "Board Geometry/Soldermask Top")
		(3 "B.Mask" user "Board Geometry/Soldermask Bottom")
		(17 "Dwgs.User" user "User.Drawings")
		(19 "Cmts.User" user "User.Comments")
		(21 "Eco1.User" user "User.Eco1")
		(23 "Eco2.User" user "User.Eco2")
		(25 "Edge.Cuts" user "Board Geometry/Outline")
		(27 "Margin" user)
		(31 "F.CrtYd" user "Package Geometry/Place Bound Top")
		(29 "B.CrtYd" user "Package Geometry/Place Bound Bottom")
		(35 "F.Fab" user "Ref Des/Assembly Top")
		(33 "B.Fab" user "Ref Des/Assembly Bottom")
	)
	(footprint ""
		(layer "F.Cu")
		(at 187.946792 -356.22103 90)
		(property "Reference" "C377"
			(at 0 0 90)
			(layer "F.SilkS")
			(hide yes)
			(effects
				(font
					(size 1.27 1.27)
				)
			)
		)
		(property "Value" ""
			(at 0 0 90)
			(layer "F.Fab")
			(effects
				(font
					(size 1.27 1.27)
				)
			)
		)
		(duplicate_pad_numbers_are_jumpers no)
		(fp_line
			(start 0.299974 -0.150114)
			(end 0.299974 0.150114)
			(stroke
				(width 0.1)
				(type default)
			)
			(layer "F.Fab")
		)
		(fp_line
			(start -0.299974 -0.150114)
			(end 0.299974 -0.150114)
			(stroke
				(width 0.1)
				(type default)
			)
			(layer "F.Fab")
		)
		(fp_line
			(start 0.299974 0.150114)
			(end -0.299974 0.150114)
			(stroke
				(width 0.1)
				(type default)
			)
			(layer "F.Fab")
		)
		(fp_line
			(start -0.299974 0.150114)
			(end -0.299974 -0.150114)
			(stroke
				(width 0.1)
				(type default)
			)
			(layer "F.Fab")
		)
		(pad "1" smd rect
			(at -0.2667 0 90)
			(size 0.3048 0.381)
			(layers "F.Cu" "F.Mask" "F.Paste")
			(net "P5E_PEX1_STN7_TX_DN<125>")
		)
		(pad "2" smd rect
			(at 0.2667 0 90)
			(size 0.3048 0.381)
			(layers "F.Cu" "F.Mask" "F.Paste")
			(net "P5E_PEX1_STN7_TX_C_DN<125>")
		)
	)
	(footprint ""
		(layer "F.Cu")
		(at 8.179054 -59.577986 -90)
		(property "Reference" "R886"
			(at 0 0 270)
			(layer "F.SilkS")
			(hide yes)
			(effects
				(font
					(size 1.27 1.27)
				)
			)
		)
		(property "Value" ""
			(at 0 0 270)
			(layer "F.Fab")
			(effects
				(font
					(size 1.27 1.27)
				)
			)
		)
		(duplicate_pad_numbers_are_jumpers no)
		(fp_line
			(start -0.7874 0.4064)
			(end -0.7874 -0.4064)
			(stroke
				(width 0.1524)
				(type default)
			)
			(layer "F.SilkS")
		)
		(fp_line
			(start 0.7874 0.4064)
			(end -0.7874 0.4064)
			(stroke
				(width 0.1524)
				(type default)
			)
			(layer "F.SilkS")
		)
		(fp_line
			(start -0.7874 -0.4064)
			(end 0.7874 -0.4064)
			(stroke
				(width 0.1524)
				(type default)
			)
			(layer "F.SilkS")
		)
		(fp_line
			(start 0.7874 -0.4064)
			(end 0.7874 0.4064)
			(stroke
				(width 0.1524)
				(type default)
			)
			(layer "F.SilkS")
		)
		(fp_line
			(start -0.67945 0.3048)
			(end -0.67945 -0.305054)
			(stroke
				(width 0.1)
				(type default)
			)
			(layer "F.Fab")
		)
		(fp_line
			(start -0.12065 0.3048)
			(end -0.67945 0.3048)
			(stroke
				(width 0.1)
				(type default)
			)
			(layer "F.Fab")
		)
		(fp_line
			(start 0.120396 0.3048)
			(end 0.120396 0.2794)
			(stroke
				(width 0.1)
				(type default)
			)
			(layer "F.Fab")
		)
		(fp_line
			(start 0.67945 0.3048)
			(end 0.120396 0.3048)
			(stroke
				(width 0.1)
				(type default)
			)
			(layer "F.Fab")
		)
		(fp_line
			(start -0.12065 0.2794)
			(end -0.12065 0.3048)
			(stroke
				(width 0.1)
				(type default)
			)
			(layer "F.Fab")
		)
		(fp_line
			(start 0.120396 0.2794)
			(end -0.12065 0.2794)
			(stroke
				(width 0.1)
				(type default)
			)
			(layer "F.Fab")
		)
		(fp_line
			(start -0.12065 -0.2794)
			(end 0.12065 -0.2794)
			(stroke
				(width 0.1)
				(type default)
			)
			(layer "F.Fab")
		)
		(fp_line
			(start 0.12065 -0.2794)
			(end 0.12065 -0.3048)
			(stroke
				(width 0.1)
				(type default)
			)
			(layer "F.Fab")
		)
		(fp_line
			(start 0.12065 -0.3048)
			(end 0.67945 -0.3048)
			(stroke
				(width 0.1)
				(type default)
			)
			(layer "F.Fab")
		)
		(fp_line
			(start 0.67945 -0.3048)
			(end 0.67945 0.3048)
			(stroke
				(width 0.1)
				(type default)
			)
			(layer "F.Fab")
		)
		(fp_line
			(start -0.67945 -0.305054)
			(end -0.12065 -0.305054)
			(stroke
				(width 0.1)
				(type default)
			)
			(layer "F.Fab")
		)
		(fp_line
			(start -0.12065 -0.305054)
			(end -0.12065 -0.2794)
			(stroke
				(width 0.1)
				(type default)
			)
			(layer "F.Fab")
		)
		(pad "1" smd circle
			(at -0.40005 0 270)
			(size 0 0)
			(layers "F.Cu" "F.Mask" "F.Paste")
			(net "P3V3_SSD0")
		)
		(pad "2" smd circle
			(at 0.40005 0 270)
			(size 0 0)
			(layers "F.Cu" "F.Mask" "F.Paste")
			(net "PWRGD_P3V3_SSD0")
		)
	)
	(footprint ""
		(layer "F.Cu")
		(at 444.713868 -232.524554)
		(property "Reference" "R6605"
			(at 0 0 0)
			(layer "F.SilkS")
			(hide yes)
			(effects
				(font
					(size 1.27 1.27)
				)
			)
		)
		(property "Value" ""
			(at 0 0 0)
			(layer "F.Fab")
			(effects
				(font
					(size 1.27 1.27)
				)
			)
		)
		(duplicate_pad_numbers_are_jumpers no)
		(fp_line
			(start -0.7874 -0.4064)
			(end 0.7874 -0.4064)
			(stroke
				(width 0.1524)
				(type default)
			)
			(layer "F.SilkS")
		)
		(fp_line
			(start -0.7874 0.4064)
			(end -0.7874 -0.4064)
			(stroke
				(width 0.1524)
				(type default)
			)
			(layer "F.SilkS")
		)
		(fp_line
			(start 0.7874 -0.4064)
			(end 0.7874 0.4064)
			(stroke
				(width 0.1524)
				(type default)
			)
			(layer "F.SilkS")
		)
		(fp_line
			(start 0.7874 0.4064)
			(end -0.7874 0.4064)
			(stroke
				(width 0.1524)
				(type default)
			)
			(layer "F.SilkS")
		)
		(fp_line
			(start -0.67945 -0.305054)
			(end -0.12065 -0.305054)
			(stroke
				(width 0.1)
				(type default)
			)
			(layer "F.Fab")
		)
		(fp_line
			(start -0.67945 0.3048)
			(end -0.67945 -0.305054)
			(stroke
				(width 0.1)
				(type default)
			)
			(layer "F.Fab")
		)
		(fp_line
			(start -0.12065 -0.305054)
			(end -0.12065 -0.2794)
			(stroke
				(width 0.1)
				(type default)
			)
			(layer "F.Fab")
		)
		(fp_line
			(start -0.12065 -0.2794)
			(end 0.12065 -0.2794)
			(stroke
				(width 0.1)
				(type default)
			)
			(layer "F.Fab")
		)
		(fp_line
			(start -0.12065 0.2794)
			(end -0.12065 0.3048)
			(stroke
				(width 0.1)
				(type default)
			)
			(layer "F.Fab")
		)
		(fp_line
			(start -0.12065 0.3048)
			(end -0.67945 0.3048)
			(stroke
				(width 0.1)
				(type default)
			)
			(layer "F.Fab")
		)
		(fp_line
			(start 0.120396 0.2794)
			(end -0.12065 0.2794)
			(stroke
				(width 0.1)
				(type default)
			)
			(layer "F.Fab")
		)
		(fp_line
			(start 0.120396 0.3048)
			(end 0.120396 0.2794)
			(stroke
				(width 0.1)
				(type default)
			)
			(layer "F.Fab")
		)
		(fp_line
			(start 0.12065 -0.3048)
			(end 0.67945 -0.3048)
			(stroke
				(width 0.1)
				(type default)
			)
			(layer "F.Fab")
		)
		(fp_line
			(start 0.12065 -0.2794)
			(end 0.12065 -0.3048)
			(stroke
				(width 0.1)
				(type default)
			)
			(layer "F.Fab")
		)
		(fp_line
			(start 0.67945 -0.3048)
			(end 0.67945 0.3048)
			(stroke
				(width 0.1)
				(type default)
			)
			(layer "F.Fab")
		)
		(fp_line
			(start 0.67945 0.3048)
			(end 0.120396 0.3048)
			(stroke
				(width 0.1)
				(type default)
			)
			(layer "F.Fab")
		)
		(pad "1" smd circle
			(at -0.40005 0)
			(size 0 0)
			(layers "F.Cu" "F.Mask" "F.Paste")
			(net "UART_PEX3_SDB_BUF_R_TX")
		)
		(pad "2" smd circle
			(at 0.40005 0)
			(size 0 0)
			(layers "F.Cu" "F.Mask" "F.Paste")
			(net "UART_PEX3_SDB_CP2108_TX")
		)
	)
	(footprint ""
		(layer "F.Cu")
		(at 251.457968 -72.766682 90)
		(property "Reference" "PC860"
			(at 0 0 90)
			(layer "F.SilkS")
			(hide yes)
			(effects
				(font
					(size 1.27 1.27)
				)
			)
		)
		(property "Value" ""
			(at 0 0 90)
			(layer "F.Fab")
			(effects
				(font
					(size 1.27 1.27)
				)
			)
		)
		(duplicate_pad_numbers_are_jumpers no)
		(fp_line
			(start 0.7874 -0.4064)
			(end 0.7874 0.4064)
			(stroke
				(width 0.1524)
				(type default)
			)
			(layer "F.SilkS")
		)
		(fp_line
			(start -0.7874 -0.4064)
			(end 0.7874 -0.4064)
			(stroke
				(width 0.1524)
				(type default)
			)
			(layer "F.SilkS")
		)
		(fp_line
			(start 0.7874 0.4064)
			(end -0.7874 0.4064)
			(stroke
				(width 0.1524)
				(type default)
			)
			(layer "F.SilkS")
		)
		(fp_line
			(start -0.7874 0.4064)
			(end -0.7874 -0.4064)
			(stroke
				(width 0.1524)
				(type default)
			)
			(layer "F.SilkS")
		)
		(fp_line
			(start -0.12065 -0.305054)
			(end -0.12065 -0.2794)
			(stroke
				(width 0.1)
				(type default)
			)
			(layer "F.Fab")
		)
		(fp_line
			(start -0.67945 -0.305054)
			(end -0.12065 -0.305054)
			(stroke
				(width 0.1)
				(type default)
			)
			(layer "F.Fab")
		)
		(fp_line
			(start 0.67945 -0.3048)
			(end 0.67945 0.3048)
			(stroke
				(width 0.1)
				(type default)
			)
			(layer "F.Fab")
		)
		(fp_line
			(start 0.12065 -0.3048)
			(end 0.67945 -0.3048)
			(stroke
				(width 0.1)
				(type default)
			)
			(layer "F.Fab")
		)
		(fp_line
			(start 0.12065 -0.2794)
			(end 0.12065 -0.3048)
			(stroke
				(width 0.1)
				(type default)
			)
			(layer "F.Fab")
		)
		(fp_line
			(start -0.12065 -0.2794)
			(end 0.12065 -0.2794)
			(stroke
				(width 0.1)
				(type default)
			)
			(layer "F.Fab")
		)
		(fp_line
			(start 0.120396 0.2794)
			(end -0.12065 0.2794)
			(stroke
				(width 0.1)
				(type default)
			)
			(layer "F.Fab")
		)
		(fp_line
			(start -0.12065 0.2794)
			(end -0.12065 0.3048)
			(stroke
				(width 0.1)
				(type default)
			)
			(layer "F.Fab")
		)
		(fp_line
			(start 0.67945 0.3048)
			(end 0.120396 0.3048)
			(stroke
				(width 0.1)
				(type default)
			)
			(layer "F.Fab")
		)
		(fp_line
			(start 0.120396 0.3048)
			(end 0.120396 0.2794)
			(stroke
				(width 0.1)
				(type default)
			)
			(layer "F.Fab")
		)
		(fp_line
			(start -0.12065 0.3048)
			(end -0.67945 0.3048)
			(stroke
				(width 0.1)
				(type default)
			)
			(layer "F.Fab")
		)
		(fp_line
			(start -0.67945 0.3048)
			(end -0.67945 -0.305054)
			(stroke
				(width 0.1)
				(type default)
			)
			(layer "F.Fab")
		)
		(pad "1" smd circle
			(at -0.40005 0 90)
			(size 0 0)
			(layers "F.Cu" "F.Mask" "F.Paste")
			(net "P12V_SSD8_CO_MODE")
		)
		(pad "2" smd circle
			(at 0.40005 0 90)
			(size 0 0)
			(layers "F.Cu" "F.Mask" "F.Paste")
			(net "GND")
		)
	)
	(footprint ""
		(layer "F.Cu")
		(at 334.130396 -118.76024 180)
		(property "Reference" "R6035"
			(at 0 0 180)
			(layer "F.SilkS")
			(hide yes)
			(effects
				(font
					(size 1.27 1.27)
				)
			)
		)
		(property "Value" ""
			(at 0 0 180)
			(layer "F.Fab")
			(effects
				(font
					(size 1.27 1.27)
				)
			)
		)
		(duplicate_pad_numbers_are_jumpers no)
		(fp_line
			(start 0.7874 0.4064)
			(end -0.7874 0.4064)
			(stroke
				(width 0.1524)
				(type default)
			)
			(layer "F.SilkS")
		)
		(fp_line
			(start 0.7874 -0.4064)
			(end 0.7874 0.4064)
			(stroke
				(width 0.1524)
				(type default)
			)
			(layer "F.SilkS")
		)
		(fp_line
			(start -0.7874 0.4064)
			(end -0.7874 -0.4064)
			(stroke
				(width 0.1524)
				(type default)
			)
			(layer "F.SilkS")
		)
		(fp_line
			(start -0.7874 -0.4064)
			(end 0.7874 -0.4064)
			(stroke
				(width 0.1524)
				(type default)
			)
			(layer "F.SilkS")
		)
		(fp_line
			(start 0.67945 0.3048)
			(end 0.120396 0.3048)
			(stroke
				(width 0.1)
				(type default)
			)
			(layer "F.Fab")
		)
		(fp_line
			(start 0.67945 -0.3048)
			(end 0.67945 0.3048)
			(stroke
				(width 0.1)
				(type default)
			)
			(layer "F.Fab")
		)
		(fp_line
			(start 0.12065 -0.2794)
			(end 0.12065 -0.3048)
			(stroke
				(width 0.1)
				(type default)
			)
			(layer "F.Fab")
		)
		(fp_line
			(start 0.12065 -0.3048)
			(end 0.67945 -0.3048)
			(stroke
				(width 0.1)
				(type default)
			)
			(layer "F.Fab")
		)
		(fp_line
			(start 0.120396 0.3048)
			(end 0.120396 0.2794)
			(stroke
				(width 0.1)
				(type default)
			)
			(layer "F.Fab")
		)
		(fp_line
			(start 0.120396 0.2794)
			(end -0.12065 0.2794)
			(stroke
				(width 0.1)
				(type default)
			)
			(layer "F.Fab")
		)
		(fp_line
			(start -0.12065 0.3048)
			(end -0.67945 0.3048)
			(stroke
				(width 0.1)
				(type default)
			)
			(layer "F.Fab")
		)
		(fp_line
			(start -0.12065 0.2794)
			(end -0.12065 0.3048)
			(stroke
				(width 0.1)
				(type default)
			)
			(layer "F.Fab")
		)
		(fp_line
			(start -0.12065 -0.2794)
			(end 0.12065 -0.2794)
			(stroke
				(width 0.1)
				(type default)
			)
			(layer "F.Fab")
		)
		(fp_line
			(start -0.12065 -0.305054)
			(end -0.12065 -0.2794)
			(stroke
				(width 0.1)
				(type default)
			)
			(layer "F.Fab")
		)
		(fp_line
			(start -0.67945 0.3048)
			(end -0.67945 -0.305054)
			(stroke
				(width 0.1)
				(type default)
			)
			(layer "F.Fab")
		)
		(fp_line
			(start -0.67945 -0.305054)
			(end -0.12065 -0.305054)
			(stroke
				(width 0.1)
				(type default)
			)
			(layer "F.Fab")
		)
		(pad "1" smd circle
			(at -0.40005 0 180)
			(size 0 0)
			(layers "F.Cu" "F.Mask" "F.Paste")
			(net "PWRGD_P3V3_NIC5_D")
		)
		(pad "2" smd circle
			(at 0.40005 0 180)
			(size 0 0)
			(layers "F.Cu" "F.Mask" "F.Paste")
			(net "PWRGD_P3V3_NIC5_R")
		)
	)
	(footprint ""
		(layer "F.Cu")
		(at 370.185696 -25.1587 -90)
		(property "Reference" "R5752"
			(at 0 0 270)
			(layer "F.SilkS")
			(hide yes)
			(effects
				(font
					(size 1.27 1.27)
				)
			)
		)
		(property "Value" ""
			(at 0 0 270)
			(layer "F.Fab")
			(effects
				(font
					(size 1.27 1.27)
				)
			)
		)
		(duplicate_pad_numbers_are_jumpers no)
		(fp_line
			(start -0.7874 0.4064)
			(end -0.7874 -0.4064)
			(stroke
				(width 0.1524)
				(type default)
			)
			(layer "F.SilkS")
		)
		(fp_line
			(start 0.7874 0.4064)
			(end -0.7874 0.4064)
			(stroke
				(width 0.1524)
				(type default)
			)
			(layer "F.SilkS")
		)
		(fp_line
			(start -0.7874 -0.4064)
			(end 0.7874 -0.4064)
			(stroke
				(width 0.1524)
				(type default)
			)
			(layer "F.SilkS")
		)
		(fp_line
			(start 0.7874 -0.4064)
			(end 0.7874 0.4064)
			(stroke
				(width 0.1524)
				(type default)
			)
			(layer "F.SilkS")
		)
		(fp_line
			(start -0.67945 0.3048)
			(end -0.67945 -0.305054)
			(stroke
				(width 0.1)
				(type default)
			)
			(layer "F.Fab")
		)
		(fp_line
			(start -0.12065 0.3048)
			(end -0.67945 0.3048)
			(stroke
				(width 0.1)
				(type default)
			)
			(layer "F.Fab")
		)
		(fp_line
			(start 0.120396 0.3048)
			(end 0.120396 0.2794)
			(stroke
				(width 0.1)
				(type default)
			)
			(layer "F.Fab")
		)
		(fp_line
			(start 0.67945 0.3048)
			(end 0.120396 0.3048)
			(stroke
				(width 0.1)
				(type default)
			)
			(layer "F.Fab")
		)
		(fp_line
			(start -0.12065 0.2794)
			(end -0.12065 0.3048)
			(stroke
				(width 0.1)
				(type default)
			)
			(layer "F.Fab")
		)
		(fp_line
			(start 0.120396 0.2794)
			(end -0.12065 0.2794)
			(stroke
				(width 0.1)
				(type default)
			)
			(layer "F.Fab")
		)
		(fp_line
			(start -0.12065 -0.2794)
			(end 0.12065 -0.2794)
			(stroke
				(width 0.1)
				(type default)
			)
			(layer "F.Fab")
		)
		(fp_line
			(start 0.12065 -0.2794)
			(end 0.12065 -0.3048)
			(stroke
				(width 0.1)
				(type default)
			)
			(layer "F.Fab")
		)
		(fp_line
			(start 0.12065 -0.3048)
			(end 0.67945 -0.3048)
			(stroke
				(width 0.1)
				(type default)
			)
			(layer "F.Fab")
		)
		(fp_line
			(start 0.67945 -0.3048)
			(end 0.67945 0.3048)
			(stroke
				(width 0.1)
				(type default)
			)
			(layer "F.Fab")
		)
		(fp_line
			(start -0.67945 -0.305054)
			(end -0.12065 -0.305054)
			(stroke
				(width 0.1)
				(type default)
			)
			(layer "F.Fab")
		)
		(fp_line
			(start -0.12065 -0.305054)
			(end -0.12065 -0.2794)
			(stroke
				(width 0.1)
				(type default)
			)
			(layer "F.Fab")
		)
		(pad "1" smd circle
			(at -0.40005 0 270)
			(size 0 0)
			(layers "F.Cu" "F.Mask" "F.Paste")
			(net "SSD12_LED_ISO_N")
		)
		(pad "2" smd circle
			(at 0.40005 0 270)
			(size 0 0)
			(layers "F.Cu" "F.Mask" "F.Paste")
			(net "SSD12_LED_ISO_R_N")
		)
	)
	(footprint ""
		(layer "F.Cu")
		(at 212.471 -228.981 180)
		(property "Reference" "R6215"
			(at 0 0 180)
			(layer "F.SilkS")
			(hide yes)
			(effects
				(font
					(size 1.27 1.27)
				)
			)
		)
		(property "Value" ""
			(at 0 0 180)
			(layer "F.Fab")
			(effects
				(font
					(size 1.27 1.27)
				)
			)
		)
		(duplicate_pad_numbers_are_jumpers no)
		(fp_line
			(start 0.7874 0.4064)
			(end -0.7874 0.4064)
			(stroke
				(width 0.1524)
				(type default)
			)
			(layer "F.SilkS")
		)
		(fp_line
			(start 0.7874 -0.4064)
			(end 0.7874 0.4064)
			(stroke
				(width 0.1524)
				(type default)
			)
			(layer "F.SilkS")
		)
		(fp_line
			(start -0.7874 0.4064)
			(end -0.7874 -0.4064)
			(stroke
				(width 0.1524)
				(type default)
			)
			(layer "F.SilkS")
		)
		(fp_line
			(start -0.7874 -0.4064)
			(end 0.7874 -0.4064)
			(stroke
				(width 0.1524)
				(type default)
			)
			(layer "F.SilkS")
		)
		(fp_line
			(start 0.67945 0.3048)
			(end 0.120396 0.3048)
			(stroke
				(width 0.1)
				(type default)
			)
			(layer "F.Fab")
		)
		(fp_line
			(start 0.67945 -0.3048)
			(end 0.67945 0.3048)
			(stroke
				(width 0.1)
				(type default)
			)
			(layer "F.Fab")
		)
		(fp_line
			(start 0.12065 -0.2794)
			(end 0.12065 -0.3048)
			(stroke
				(width 0.1)
				(type default)
			)
			(layer "F.Fab")
		)
		(fp_line
			(start 0.12065 -0.3048)
			(end 0.67945 -0.3048)
			(stroke
				(width 0.1)
				(type default)
			)
			(layer "F.Fab")
		)
		(fp_line
			(start 0.120396 0.3048)
			(end 0.120396 0.2794)
			(stroke
				(width 0.1)
				(type default)
			)
			(layer "F.Fab")
		)
		(fp_line
			(start 0.120396 0.2794)
			(end -0.12065 0.2794)
			(stroke
				(width 0.1)
				(type default)
			)
			(layer "F.Fab")
		)
		(fp_line
			(start -0.12065 0.3048)
			(end -0.67945 0.3048)
			(stroke
				(width 0.1)
				(type default)
			)
			(layer "F.Fab")
		)
		(fp_line
			(start -0.12065 0.2794)
			(end -0.12065 0.3048)
			(stroke
				(width 0.1)
				(type default)
			)
			(layer "F.Fab")
		)
		(fp_line
			(start -0.12065 -0.2794)
			(end 0.12065 -0.2794)
			(stroke
				(width 0.1)
				(type default)
			)
			(layer "F.Fab")
		)
		(fp_line
			(start -0.12065 -0.305054)
			(end -0.12065 -0.2794)
			(stroke
				(width 0.1)
				(type default)
			)
			(layer "F.Fab")
		)
		(fp_line
			(start -0.67945 0.3048)
			(end -0.67945 -0.305054)
			(stroke
				(width 0.1)
				(type default)
			)
			(layer "F.Fab")
		)
		(fp_line
			(start -0.67945 -0.305054)
			(end -0.12065 -0.305054)
			(stroke
				(width 0.1)
				(type default)
			)
			(layer "F.Fab")
		)
		(pad "1" smd circle
			(at -0.40005 0 180)
			(size 0 0)
			(layers "F.Cu" "F.Mask" "F.Paste")
			(net "PRSNT_DBV2_SLIMSAS_R")
		)
		(pad "2" smd circle
			(at 0.40005 0 180)
			(size 0 0)
			(layers "F.Cu" "F.Mask" "F.Paste")
			(net "PRSNT_DBV2_SLIMSAS")
		)
	)
)
